# S9S_MB_2U (Grand Teton) — schematic netlist excerpt (pin names and nets, part order shuffled) for the footprints in the layout excerpt that follows; sources: Cadence DE-HDL packaged netlist, KiCad conversion of 03242023_DA0F0TMBIJ0_F0T_Motherboard_J_brd_V01_OCP.brd

R4202  Q_RES  1K 1% EMPTY  pkg 0402LF  page 170 : A = P3V3_AUX ; B = U272_2_ADD0
C923  Q_CAP_DIFFBUS  DIFF BUS_0.22UF 6.3V 20% X6S  pkg C0201  page 173 : \1\ = P5E_CPU0_PE0_TX_C_DP<5> ; \2\ = P5E_CPU0_PE0_TX_DP<5>
R1724  Q_RES  0 5% CHIP  pkg 0402LF  page 208 : A = XTAL_CLK_GEN1_25M_X1_R ; B = XTAL_CLK_GEN1_25M_X1

(kicad_pcb
	(version 20260206)
	(generator "pcbnew")
	(generator_version "10.0")
	(general
		(thickness 1.6)
		(legacy_teardrops no)
	)
	(paper "A4")
	(title_block
		(title "03242023_DA0F0TMBIJ0_F0T_Motherboard_J_brd_V01_OCP.brd")
		(comment 1 "Grand Teton / footprints 931-933 of 6105")
	)
	(layers
		(0 "F.Cu" signal "TOP")
		(4 "In1.Cu" signal "GND")
		(6 "In2.Cu" signal "IN1")
		(8 "In3.Cu" signal "GND1")
		(10 "In4.Cu" signal "IN2")
		(12 "In5.Cu" signal "GND2")
		(14 "In6.Cu" signal "IN3")
		(16 "In7.Cu" signal "GND3")
		(18 "In8.Cu" signal "VCC")
		(20 "In9.Cu" signal "VCC1")
		(22 "In10.Cu" signal "GND4")
		(24 "In11.Cu" signal "IN4")
		(26 "In12.Cu" signal "GND5")
		(28 "In13.Cu" signal "IN5")
		(30 "In14.Cu" signal "GND6")
		(32 "In15.Cu" signal "IN6")
		(34 "In16.Cu" signal "GND7")
		(2 "B.Cu" signal "BOTTOM")
		(9 "F.Adhes" user "F.Adhesive")
		(11 "B.Adhes" user "B.Adhesive")
		(13 "F.Paste" user "Package Geometry/Pastemask Top")
		(15 "B.Paste" user "Package Geometry/Pastemask Bottom")
		(5 "F.SilkS" user "Ref Des/Silkscreen Top")
		(7 "B.SilkS" user "Ref Des/Silkscreen Bottom")
		(1 "F.Mask" user "Board Geometry/Soldermask Top")
		(3 "B.Mask" user "Board Geometry/Soldermask Bottom")
		(17 "Dwgs.User" user "User.Drawings")
		(19 "Cmts.User" user "User.Comments")
		(21 "Eco1.User" user "User.Eco1")
		(23 "Eco2.User" user "User.Eco2")
		(25 "Edge.Cuts" user "Board Geometry/Outline")
		(27 "Margin" user)
		(31 "F.CrtYd" user "Package Geometry/Place Bound Top")
		(29 "B.CrtYd" user "Package Geometry/Place Bound Bottom")
		(35 "F.Fab" user "Ref Des/Assembly Top")
		(33 "B.Fab" user "Ref Des/Assembly Bottom")
	)
	(footprint ""
		(layer "F.Cu")
		(at 249.374406 -92.06484 90)
		(property "Reference" "R1724"
			(at 0 0 90)
			(layer "F.SilkS")
			(hide yes)
			(effects
				(font
					(size 1.27 1.27)
				)
			)
		)
		(property "Value" ""
			(at 0 0 90)
			(layer "F.Fab")
			(effects
				(font
					(size 1.27 1.27)
				)
			)
		)
		(duplicate_pad_numbers_are_jumpers no)
		(fp_line
			(start 0.7874 -0.4064)
			(end 0.7874 0.4064)
			(stroke
				(width 0.1524)
				(type default)
			)
			(layer "F.SilkS")
		)
		(fp_line
			(start -0.7874 -0.4064)
			(end 0.7874 -0.4064)
			(stroke
				(width 0.1524)
				(type default)
			)
			(layer "F.SilkS")
		)
		(fp_line
			(start 0.7874 0.4064)
			(end -0.7874 0.4064)
			(stroke
				(width 0.1524)
				(type default)
			)
			(layer "F.SilkS")
		)
		(fp_line
			(start -0.7874 0.4064)
			(end -0.7874 -0.4064)
			(stroke
				(width 0.1524)
				(type default)
			)
			(layer "F.SilkS")
		)
		(fp_line
			(start -0.12065 -0.305054)
			(end -0.12065 -0.2794)
			(stroke
				(width 0.1)
				(type default)
			)
			(layer "F.Fab")
		)
		(fp_line
			(start -0.67945 -0.305054)
			(end -0.12065 -0.305054)
			(stroke
				(width 0.1)
				(type default)
			)
			(layer "F.Fab")
		)
		(fp_line
			(start 0.67945 -0.3048)
			(end 0.67945 0.3048)
			(stroke
				(width 0.1)
				(type default)
			)
			(layer "F.Fab")
		)
		(fp_line
			(start 0.12065 -0.3048)
			(end 0.67945 -0.3048)
			(stroke
				(width 0.1)
				(type default)
			)
			(layer "F.Fab")
		)
		(fp_line
			(start 0.12065 -0.2794)
			(end 0.12065 -0.3048)
			(stroke
				(width 0.1)
				(type default)
			)
			(layer "F.Fab")
		)
		(fp_line
			(start -0.12065 -0.2794)
			(end 0.12065 -0.2794)
			(stroke
				(width 0.1)
				(type default)
			)
			(layer "F.Fab")
		)
		(fp_line
			(start 0.120396 0.2794)
			(end -0.12065 0.2794)
			(stroke
				(width 0.1)
				(type default)
			)
			(layer "F.Fab")
		)
		(fp_line
			(start -0.12065 0.2794)
			(end -0.12065 0.3048)
			(stroke
				(width 0.1)
				(type default)
			)
			(layer "F.Fab")
		)
		(fp_line
			(start 0.67945 0.3048)
			(end 0.120396 0.3048)
			(stroke
				(width 0.1)
				(type default)
			)
			(layer "F.Fab")
		)
		(fp_line
			(start 0.120396 0.3048)
			(end 0.120396 0.2794)
			(stroke
				(width 0.1)
				(type default)
			)
			(layer "F.Fab")
		)
		(fp_line
			(start -0.12065 0.3048)
			(end -0.67945 0.3048)
			(stroke
				(width 0.1)
				(type default)
			)
			(layer "F.Fab")
		)
		(fp_line
			(start -0.67945 0.3048)
			(end -0.67945 -0.305054)
			(stroke
				(width 0.1)
				(type default)
			)
			(layer "F.Fab")
		)
		(pad "1" smd circle
			(at -0.40005 0 90)
			(size 0 0)
			(layers "F.Cu" "F.Mask" "F.Paste")
			(net "XTAL_CLK_GEN1_25M_X1_R")
		)
		(pad "2" smd circle
			(at 0.40005 0 90)
			(size 0 0)
			(layers "F.Cu" "F.Mask" "F.Paste")
			(net "XTAL_CLK_GEN1_25M_X1")
		)
	)
	(footprint ""
		(layer "F.Cu")
		(at 99.457002 -417.631626 90)
		(property "Reference" "R4202"
			(at 0 0 90)
			(layer "F.SilkS")
			(hide yes)
			(effects
				(font
					(size 1.27 1.27)
				)
			)
		)
		(property "Value" ""
			(at 0 0 90)
			(layer "F.Fab")
			(effects
				(font
					(size 1.27 1.27)
				)
			)
		)
		(duplicate_pad_numbers_are_jumpers no)
		(fp_line
			(start 0.7874 -0.4064)
			(end 0.7874 0.4064)
			(stroke
				(width 0.1524)
				(type default)
			)
			(layer "F.SilkS")
		)
		(fp_line
			(start -0.7874 -0.4064)
			(end 0.7874 -0.4064)
			(stroke
				(width 0.1524)
				(type default)
			)
			(layer "F.SilkS")
		)
		(fp_line
			(start 0.7874 0.4064)
			(end -0.7874 0.4064)
			(stroke
				(width 0.1524)
				(type default)
			)
			(layer "F.SilkS")
		)
		(fp_line
			(start -0.7874 0.4064)
			(end -0.7874 -0.4064)
			(stroke
				(width 0.1524)
				(type default)
			)
			(layer "F.SilkS")
		)
		(fp_line
			(start -0.12065 -0.305054)
			(end -0.12065 -0.2794)
			(stroke
				(width 0.1)
				(type default)
			)
			(layer "F.Fab")
		)
		(fp_line
			(start -0.67945 -0.305054)
			(end -0.12065 -0.305054)
			(stroke
				(width 0.1)
				(type default)
			)
			(layer "F.Fab")
		)
		(fp_line
			(start 0.67945 -0.3048)
			(end 0.67945 0.3048)
			(stroke
				(width 0.1)
				(type default)
			)
			(layer "F.Fab")
		)
		(fp_line
			(start 0.12065 -0.3048)
			(end 0.67945 -0.3048)
			(stroke
				(width 0.1)
				(type default)
			)
			(layer "F.Fab")
		)
		(fp_line
			(start 0.12065 -0.2794)
			(end 0.12065 -0.3048)
			(stroke
				(width 0.1)
				(type default)
			)
			(layer "F.Fab")
		)
		(fp_line
			(start -0.12065 -0.2794)
			(end 0.12065 -0.2794)
			(stroke
				(width 0.1)
				(type default)
			)
			(layer "F.Fab")
		)
		(fp_line
			(start 0.120396 0.2794)
			(end -0.12065 0.2794)
			(stroke
				(width 0.1)
				(type default)
			)
			(layer "F.Fab")
		)
		(fp_line
			(start -0.12065 0.2794)
			(end -0.12065 0.3048)
			(stroke
				(width 0.1)
				(type default)
			)
			(layer "F.Fab")
		)
		(fp_line
			(start 0.67945 0.3048)
			(end 0.120396 0.3048)
			(stroke
				(width 0.1)
				(type default)
			)
			(layer "F.Fab")
		)
		(fp_line
			(start 0.120396 0.3048)
			(end 0.120396 0.2794)
			(stroke
				(width 0.1)
				(type default)
			)
			(layer "F.Fab")
		)
		(fp_line
			(start -0.12065 0.3048)
			(end -0.67945 0.3048)
			(stroke
				(width 0.1)
				(type default)
			)
			(layer "F.Fab")
		)
		(fp_line
			(start -0.67945 0.3048)
			(end -0.67945 -0.305054)
			(stroke
				(width 0.1)
				(type default)
			)
			(layer "F.Fab")
		)
		(pad "1" smd circle
			(at -0.40005 0 90)
			(size 0 0)
			(layers "F.Cu" "F.Mask" "F.Paste")
			(net "P3V3_AUX")
		)
		(pad "2" smd circle
			(at 0.40005 0 90)
			(size 0 0)
			(layers "F.Cu" "F.Mask" "F.Paste")
			(net "U272_2_ADD0")
		)
	)
	(footprint ""
		(layer "F.Cu")
		(at 336.847688 -408.517344 -90)
		(property "Reference" "C923"
			(at 0 0 270)
			(layer "F.SilkS")
			(hide yes)
			(effects
				(font
					(size 1.27 1.27)
				)
			)
		)
		(property "Value" ""
			(at 0 0 270)
			(layer "F.Fab")
			(effects
				(font
					(size 1.27 1.27)
				)
			)
		)
		(duplicate_pad_numbers_are_jumpers no)
		(fp_line
			(start -0.299974 0.150114)
			(end -0.299974 -0.150114)
			(stroke
				(width 0.1)
				(type default)
			)
			(layer "F.Fab")
		)
		(fp_line
			(start 0.299974 0.150114)
			(end -0.299974 0.150114)
			(stroke
				(width 0.1)
				(type default)
			)
			(layer "F.Fab")
		)
		(fp_line
			(start -0.299974 -0.150114)
			(end 0.299974 -0.150114)
			(stroke
				(width 0.1)
				(type default)
			)
			(layer "F.Fab")
		)
		(fp_line
			(start 0.299974 -0.150114)
			(end 0.299974 0.150114)
			(stroke
				(width 0.1)
				(type default)
			)
			(layer "F.Fab")
		)
		(pad "1" smd rect
			(at -0.2667 0 270)
			(size 0.3048 0.381)
			(layers "F.Cu" "F.Mask" "F.Paste")
			(net "P5E_CPU0_PE0_TX_C_DP<5>")
		)
		(pad "2" smd rect
			(at 0.2667 0 270)
			(size 0.3048 0.381)
			(layers "F.Cu" "F.Mask" "F.Paste")
			(net "P5E_CPU0_PE0_TX_DP<5>")
		)
	)
)
